# S9S_MB_2U (Grand Teton) — schematic netlist excerpt (pin names and nets, part order shuffled) for the footprints in the layout excerpt that follows; sources: Cadence DE-HDL packaged netlist, KiCad conversion of 03242023_DA0F0TMBIJ0_F0T_Motherboard_J_brd_V01_OCP.brd

X43  TP_TDR_4P_FTS  TP_TDR_4P_DIP EMPTY  pkg TH  page 310
  S1  = UNNAMED_310_TPTDR4PFTS_I7_S2
  P1  = T1_GND
  P2  = T1_GND
  S2  = UNNAMED_310_TPTDR4PFTS_I7_S1

PC1201  Q_CAPP  560UF 2.5V 20% OSCON  pkg THLF  page 290 : A = PVCCFA_EHV_FIVRA_CPU1 ; B = GND

(kicad_pcb
	(version 20260206)
	(generator "pcbnew")
	(generator_version "10.0")
	(general
		(thickness 1.6)
		(legacy_teardrops no)
	)
	(paper "A4")
	(title_block
		(title "03242023_DA0F0TMBIJ0_F0T_Motherboard_J_brd_V01_OCP.brd")
		(comment 1 "Grand Teton / footprints 3094-3095 of 6105")
	)
	(layers
		(0 "F.Cu" signal "TOP")
		(4 "In1.Cu" signal "GND")
		(6 "In2.Cu" signal "IN1")
		(8 "In3.Cu" signal "GND1")
		(10 "In4.Cu" signal "IN2")
		(12 "In5.Cu" signal "GND2")
		(14 "In6.Cu" signal "IN3")
		(16 "In7.Cu" signal "GND3")
		(18 "In8.Cu" signal "VCC")
		(20 "In9.Cu" signal "VCC1")
		(22 "In10.Cu" signal "GND4")
		(24 "In11.Cu" signal "IN4")
		(26 "In12.Cu" signal "GND5")
		(28 "In13.Cu" signal "IN5")
		(30 "In14.Cu" signal "GND6")
		(32 "In15.Cu" signal "IN6")
		(34 "In16.Cu" signal "GND7")
		(2 "B.Cu" signal "BOTTOM")
		(9 "F.Adhes" user "F.Adhesive")
		(11 "B.Adhes" user "B.Adhesive")
		(13 "F.Paste" user "Package Geometry/Pastemask Top")
		(15 "B.Paste" user "Package Geometry/Pastemask Bottom")
		(5 "F.SilkS" user "Ref Des/Silkscreen Top")
		(7 "B.SilkS" user "Ref Des/Silkscreen Bottom")
		(1 "F.Mask" user "Board Geometry/Soldermask Top")
		(3 "B.Mask" user "Board Geometry/Soldermask Bottom")
		(17 "Dwgs.User" user "User.Drawings")
		(19 "Cmts.User" user "User.Comments")
		(21 "Eco1.User" user "User.Eco1")
		(23 "Eco2.User" user "User.Eco2")
		(25 "Edge.Cuts" user "Board Geometry/Outline")
		(27 "Margin" user)
		(31 "F.CrtYd" user "Package Geometry/Place Bound Top")
		(29 "B.CrtYd" user "Package Geometry/Place Bound Bottom")
		(35 "F.Fab" user "Ref Des/Assembly Top")
		(33 "B.Fab" user "Ref Des/Assembly Bottom")
	)
	(footprint ""
		(layer "F.Cu")
		(at 479.84537 -184.606692 -90)
		(property "Reference" "X43"
			(at 2.361692 4.7117 90)
			(unlocked yes)
			(layer "F.SilkS")
			(effects
				(font
					(size 0.7874 0.5842)
					(thickness 0.1524)
				)
				(justify left)
			)
		)
		(property "Value" ""
			(at 0 0 270)
			(layer "F.Fab")
			(effects
				(font
					(size 1.27 1.27)
				)
			)
		)
		(property "Device Type" "TP_TDR_4P_FTS_TH-TP_TDR_4P_DIPA"
			(at 1.30175 1.27 0)
			(unlocked yes)
			(layer "F.Fab")
			(hide yes)
			(effects
				(font
					(size 0.635 0.4064)
					(thickness 0.1524)
				)
			)
		)
		(property "User Part Number" "N_A"
			(at 1.30175 1.27 0)
			(unlocked yes)
			(layer "Cmts.User")
			(hide yes)
			(effects
				(font
					(size 0.635 0.4064)
					(thickness 0.1524)
				)
			)
		)
		(duplicate_pad_numbers_are_jumpers no)
		(fp_line
			(start 0 3.81)
			(end 2.54 3.81)
			(stroke
				(width 0.1524)
				(type default)
			)
			(layer "F.SilkS")
		)
		(fp_line
			(start 2.54 3.81)
			(end 2.54 3.6703)
			(stroke
				(width 0.1524)
				(type default)
			)
			(layer "F.SilkS")
		)
		(fp_line
			(start 0 3.175)
			(end 0 3.81)
			(stroke
				(width 0.1524)
				(type default)
			)
			(layer "F.SilkS")
		)
		(fp_line
			(start 2.54 1.4097)
			(end 2.54 1.1303)
			(stroke
				(width 0.1524)
				(type default)
			)
			(layer "F.SilkS")
		)
		(fp_line
			(start 0 0.635)
			(end 0 1.905)
			(stroke
				(width 0.1524)
				(type default)
			)
			(layer "F.SilkS")
		)
		(fp_line
			(start 2.54 -1.1303)
			(end 2.54 -1.27)
			(stroke
				(width 0.1524)
				(type default)
			)
			(layer "F.SilkS")
		)
		(fp_line
			(start 0 -1.27)
			(end 0 -0.635)
			(stroke
				(width 0.1524)
				(type default)
			)
			(layer "F.SilkS")
		)
		(fp_line
			(start 2.54 -1.27)
			(end 0 -1.27)
			(stroke
				(width 0.1524)
				(type default)
			)
			(layer "F.SilkS")
		)
		(fp_poly
			(pts
				(xy -0.761746 0) (xy -2.285746 -0.762) (xy -2.285746 0.762)
			)
			(stroke
				(width 0)
				(type default)
			)
			(fill yes)
			(layer "F.SilkS")
		)
		(fp_line
			(start 0 3.81)
			(end 2.54 3.81)
			(stroke
				(width 0.1)
				(type default)
			)
			(layer "F.Fab")
		)
		(fp_line
			(start 2.54 3.81)
			(end 2.54 -1.27)
			(stroke
				(width 0.1)
				(type default)
			)
			(layer "F.Fab")
		)
		(fp_line
			(start 0 -1.27)
			(end 0 3.81)
			(stroke
				(width 0.1)
				(type default)
			)
			(layer "F.Fab")
		)
		(fp_line
			(start 2.54 -1.27)
			(end 0 -1.27)
			(stroke
				(width 0.1)
				(type default)
			)
			(layer "F.Fab")
		)
		(fp_poly
			(pts
				(xy -0.761746 0) (xy -2.285746 -0.762) (xy -2.285746 0.762)
			)
			(stroke
				(width 0)
				(type default)
			)
			(fill yes)
			(layer "F.Fab")
		)
		(pad "1" thru_hole circle
			(at 0 0 270)
			(size 1.0033 1.0033)
			(drill 0.249936)
			(layers "*.Cu" "*.Mask")
			(remove_unused_layers no)
			(net "TDR_DIFF_85_NECK_IN2_DN")
			(clearance 0.10795)
			(thermal_gap 0.10795)
			(padstack
				(mode front_inner_back)
				(layer "Inner"
					(shape circle)
					(size 0.8001 0.8001)
					(clearance 0.1524)
				)
				(layer "B.Cu"
					(shape circle)
					(size 1.0033 1.0033)
					(clearance 0.10795)
				)
			)
		)
		(pad "2" thru_hole circle
			(at 2.54 0 270)
			(size 1.9939 1.9939)
			(drill 0.249936)
			(layers "*.Cu" "*.Mask")
			(remove_unused_layers no)
			(net "T1_GND")
			(clearance 0.10795)
			(thermal_gap 0.10795)
			(padstack
				(mode front_inner_back)
				(layer "Inner"
					(shape circle)
					(size 0.8001 0.8001)
					(clearance 0.1524)
				)
				(layer "B.Cu"
					(shape circle)
					(size 1.9939 1.9939)
					(clearance 0.10795)
				)
			)
		)
		(pad "3" thru_hole circle
			(at 2.54 2.54 270)
			(size 1.9939 1.9939)
			(drill 0.249936)
			(layers "*.Cu" "*.Mask")
			(remove_unused_layers no)
			(net "T1_GND")
			(clearance 0.10795)
			(thermal_gap 0.10795)
			(padstack
				(mode front_inner_back)
				(layer "Inner"
					(shape circle)
					(size 0.8001 0.8001)
					(clearance 0.1524)
				)
				(layer "B.Cu"
					(shape circle)
					(size 1.9939 1.9939)
					(clearance 0.10795)
				)
			)
		)
		(pad "4" thru_hole circle
			(at 0 2.54 270)
			(size 1.0033 1.0033)
			(drill 0.249936)
			(layers "*.Cu" "*.Mask")
			(remove_unused_layers no)
			(net "TDR_DIFF_85_NECK_IN2_DP")
			(clearance 0.10795)
			(thermal_gap 0.10795)
			(padstack
				(mode front_inner_back)
				(layer "Inner"
					(shape circle)
					(size 0.8001 0.8001)
					(clearance 0.1524)
				)
				(layer "B.Cu"
					(shape circle)
					(size 1.0033 1.0033)
					(clearance 0.10795)
				)
			)
		)
	)
	(footprint ""
		(layer "F.Cu")
		(at 183.353964 -337.483958)
		(property "Reference" "PC1201"
			(at 0 0 0)
			(layer "F.SilkS")
			(hide yes)
			(effects
				(font
					(size 1.27 1.27)
				)
			)
		)
		(property "Value" ""
			(at 0 0 0)
			(layer "F.Fab")
			(effects
				(font
					(size 1.27 1.27)
				)
			)
		)
		(duplicate_pad_numbers_are_jumpers no)
		(fp_line
			(start 2.750058 0.999998)
			(end -2.750058 0.999998)
			(stroke
				(width 0.1524)
				(type default)
			)
			(layer "F.SilkS")
		)
		(fp_circle
			(center 0 0.999998)
			(end 2.750058 0.999998)
			(stroke
				(width 0.1524)
				(type default)
			)
			(fill no)
			(layer "F.SilkS")
		)
		(fp_poly
			(pts
				(arc
					(start 2.750058 0.999998)
					(mid 0 3.750056)
					(end -2.750058 0.999998)
				)
			)
			(stroke
				(width 0)
				(type default)
			)
			(fill yes)
			(layer "F.SilkS")
		)
		(fp_circle
			(center 0 0.999998)
			(end 2.750058 0.999998)
			(stroke
				(width 0.1)
				(type default)
			)
			(fill no)
			(layer "F.Fab")
		)
		(pad "1" thru_hole rect
			(at 0 0)
			(size 1.5748 1.5748)
			(drill 1.0668)
			(layers "*.Cu" "*.Mask")
			(remove_unused_layers no)
			(net "PVCCFA_EHV_FIVRA_CPU1")
			(clearance 0)
			(padstack
				(mode front_inner_back)
				(layer "Inner"
					(shape circle)
					(size 1.5748 1.5748)
					(clearance 0)
				)
				(layer "B.Cu"
					(shape rect)
					(size 1.5748 1.5748)
					(clearance 0)
				)
			)
		)
		(pad "2" thru_hole circle
			(at 0 1.999996)
			(size 1.5748 1.5748)
			(drill 1.0668)
			(layers "*.Cu" "*.Mask")
			(remove_unused_layers no)
			(net "GND")
			(clearance 0)
		)
	)
)
